(kicad_pcb
	(version 20260206)
	(generator "pcbnew")
	(generator_version "10.0")
	(general
		(thickness 1.6)
		(legacy_teardrops no)
	)
	(paper "A4")
	(title_block
		(title "12092022_DA0F0TMDCD0_F0T_Management_Board_D_brd_V3_OCP.brd")
		(comment 1 "Grand Teton / footprints 1214-1218 of 1440")
	)
	(layers
		(0 "F.Cu" signal "TOP")
		(4 "In1.Cu" signal "GND")
		(6 "In2.Cu" signal "IN1")
		(8 "In3.Cu" signal "GND1")
		(10 "In4.Cu" signal "IN2")
		(12 "In5.Cu" signal "VCC")
		(14 "In6.Cu" signal "VCC1")
		(16 "In7.Cu" signal "IN3")
		(18 "In8.Cu" signal "GND2")
		(20 "In9.Cu" signal "IN4")
		(22 "In10.Cu" signal "GND3")
		(2 "B.Cu" signal "BOTTOM")
		(9 "F.Adhes" user "F.Adhesive")
		(11 "B.Adhes" user "B.Adhesive")
		(13 "F.Paste" user "Package Geometry/Pastemask Top")
		(15 "B.Paste" user "Package Geometry/Pastemask Bottom")
		(5 "F.SilkS" user "Ref Des/Silkscreen Top")
		(7 "B.SilkS" user "Ref Des/Silkscreen Bottom")
		(1 "F.Mask" user "Board Geometry/Soldermask Top")
		(3 "B.Mask" user "Board Geometry/Soldermask Bottom")
		(17 "Dwgs.User" user "User.Drawings")
		(19 "Cmts.User" user "User.Comments")
		(21 "Eco1.User" user "User.Eco1")
		(23 "Eco2.User" user "User.Eco2")
		(25 "Edge.Cuts" user "Board Geometry/Outline")
		(27 "Margin" user)
		(31 "F.CrtYd" user "Package Geometry/Place Bound Top")
		(29 "B.CrtYd" user "Package Geometry/Place Bound Bottom")
		(35 "F.Fab" user "Ref Des/Assembly Top")
		(33 "B.Fab" user "Ref Des/Assembly Bottom")
	)
	(footprint ""
		(layer "B.Cu")
		(at 64.643 -13.081 180)
		(property "Reference" "R630"
			(at 0 0 0)
			(layer "B.SilkS")
			(hide yes)
			(effects
				(font
					(size 1.27 1.27)
				)
				(justify mirror)
			)
		)
		(property "Value" ""
			(at 0 0 0)
			(layer "B.Fab")
			(effects
				(font
					(size 1.27 1.27)
				)
				(justify mirror)
			)
		)
		(duplicate_pad_numbers_are_jumpers no)
		(fp_line
			(start 0.7874 0.4064)
			(end 0.7874 -0.4064)
			(stroke
				(width 0.1524)
				(type default)
			)
			(layer "B.SilkS")
		)
		(fp_line
			(start 0.7874 -0.4064)
			(end -0.7874 -0.4064)
			(stroke
				(width 0.1524)
				(type default)
			)
			(layer "B.SilkS")
		)
		(fp_line
			(start -0.7874 0.4064)
			(end 0.7874 0.4064)
			(stroke
				(width 0.1524)
				(type default)
			)
			(layer "B.SilkS")
		)
		(fp_line
			(start -0.7874 -0.4064)
			(end -0.7874 0.4064)
			(stroke
				(width 0.1524)
				(type default)
			)
			(layer "B.SilkS")
		)
		(fp_line
			(start 0.67945 0.3048)
			(end 0.67945 -0.305054)
			(stroke
				(width 0.1)
				(type default)
			)
			(layer "B.Fab")
		)
		(fp_line
			(start 0.67945 -0.305054)
			(end 0.12065 -0.305054)
			(stroke
				(width 0.1)
				(type default)
			)
			(layer "B.Fab")
		)
		(fp_line
			(start 0.12065 0.3048)
			(end 0.67945 0.3048)
			(stroke
				(width 0.1)
				(type default)
			)
			(layer "B.Fab")
		)
		(fp_line
			(start 0.12065 0.2794)
			(end 0.12065 0.3048)
			(stroke
				(width 0.1)
				(type default)
			)
			(layer "B.Fab")
		)
		(fp_line
			(start 0.12065 -0.2794)
			(end -0.12065 -0.2794)
			(stroke
				(width 0.1)
				(type default)
			)
			(layer "B.Fab")
		)
		(fp_line
			(start 0.12065 -0.305054)
			(end 0.12065 -0.2794)
			(stroke
				(width 0.1)
				(type default)
			)
			(layer "B.Fab")
		)
		(fp_line
			(start -0.120396 0.3048)
			(end -0.120396 0.2794)
			(stroke
				(width 0.1)
				(type default)
			)
			(layer "B.Fab")
		)
		(fp_line
			(start -0.120396 0.2794)
			(end 0.12065 0.2794)
			(stroke
				(width 0.1)
				(type default)
			)
			(layer "B.Fab")
		)
		(fp_line
			(start -0.12065 -0.2794)
			(end -0.12065 -0.3048)
			(stroke
				(width 0.1)
				(type default)
			)
			(layer "B.Fab")
		)
		(fp_line
			(start -0.12065 -0.3048)
			(end -0.67945 -0.3048)
			(stroke
				(width 0.1)
				(type default)
			)
			(layer "B.Fab")
		)
		(fp_line
			(start -0.67945 0.3048)
			(end -0.120396 0.3048)
			(stroke
				(width 0.1)
				(type default)
			)
			(layer "B.Fab")
		)
		(fp_line
			(start -0.67945 -0.3048)
			(end -0.67945 0.3048)
			(stroke
				(width 0.1)
				(type default)
			)
			(layer "B.Fab")
		)
		(pad "1" smd circle
			(at 0.40005 0)
			(size 0 0)
			(layers "B.Cu" "B.Mask" "B.Paste")
			(net "P3V3_AUX")
		)
		(pad "2" smd circle
			(at -0.40005 0)
			(size 0 0)
			(layers "B.Cu" "B.Mask" "B.Paste")
			(net "PU_J13_P1")
		)
	)
	(footprint ""
		(layer "B.Cu")
		(at 52.384452 -60.134246 90)
		(property "Reference" "C279"
			(at 0 0 90)
			(layer "B.SilkS")
			(hide yes)
			(effects
				(font
					(size 1.27 1.27)
				)
				(justify mirror)
			)
		)
		(property "Value" ""
			(at 0 0 90)
			(layer "B.Fab")
			(effects
				(font
					(size 1.27 1.27)
				)
				(justify mirror)
			)
		)
		(duplicate_pad_numbers_are_jumpers no)
		(fp_line
			(start 0.7874 -0.4064)
			(end -0.7874 -0.4064)
			(stroke
				(width 0.1524)
				(type default)
			)
			(layer "B.SilkS")
		)
		(fp_line
			(start -0.7874 -0.4064)
			(end -0.7874 0.4064)
			(stroke
				(width 0.1524)
				(type default)
			)
			(layer "B.SilkS")
		)
		(fp_line
			(start 0.7874 0.4064)
			(end 0.7874 -0.4064)
			(stroke
				(width 0.1524)
				(type default)
			)
			(layer "B.SilkS")
		)
		(fp_line
			(start -0.7874 0.4064)
			(end 0.7874 0.4064)
			(stroke
				(width 0.1524)
				(type default)
			)
			(layer "B.SilkS")
		)
		(fp_line
			(start 0.67945 -0.305054)
			(end 0.12065 -0.305054)
			(stroke
				(width 0.1)
				(type default)
			)
			(layer "B.Fab")
		)
		(fp_line
			(start 0.12065 -0.305054)
			(end 0.12065 -0.2794)
			(stroke
				(width 0.1)
				(type default)
			)
			(layer "B.Fab")
		)
		(fp_line
			(start -0.12065 -0.3048)
			(end -0.67945 -0.3048)
			(stroke
				(width 0.1)
				(type default)
			)
			(layer "B.Fab")
		)
		(fp_line
			(start -0.67945 -0.3048)
			(end -0.67945 0.3048)
			(stroke
				(width 0.1)
				(type default)
			)
			(layer "B.Fab")
		)
		(fp_line
			(start 0.12065 -0.2794)
			(end -0.12065 -0.2794)
			(stroke
				(width 0.1)
				(type default)
			)
			(layer "B.Fab")
		)
		(fp_line
			(start -0.12065 -0.2794)
			(end -0.12065 -0.3048)
			(stroke
				(width 0.1)
				(type default)
			)
			(layer "B.Fab")
		)
		(fp_line
			(start 0.12065 0.2794)
			(end 0.12065 0.3048)
			(stroke
				(width 0.1)
				(type default)
			)
			(layer "B.Fab")
		)
		(fp_line
			(start -0.120396 0.2794)
			(end 0.12065 0.2794)
			(stroke
				(width 0.1)
				(type default)
			)
			(layer "B.Fab")
		)
		(fp_line
			(start 0.67945 0.3048)
			(end 0.67945 -0.305054)
			(stroke
				(width 0.1)
				(type default)
			)
			(layer "B.Fab")
		)
		(fp_line
			(start 0.12065 0.3048)
			(end 0.67945 0.3048)
			(stroke
				(width 0.1)
				(type default)
			)
			(layer "B.Fab")
		)
		(fp_line
			(start -0.120396 0.3048)
			(end -0.120396 0.2794)
			(stroke
				(width 0.1)
				(type default)
			)
			(layer "B.Fab")
		)
		(fp_line
			(start -0.67945 0.3048)
			(end -0.120396 0.3048)
			(stroke
				(width 0.1)
				(type default)
			)
			(layer "B.Fab")
		)
		(pad "1" smd circle
			(at 0.40005 0 270)
			(size 0 0)
			(layers "B.Cu" "B.Mask" "B.Paste")
			(net "ADCVREFEXT1")
		)
		(pad "2" smd circle
			(at -0.40005 0 270)
			(size 0 0)
			(layers "B.Cu" "B.Mask" "B.Paste")
			(net "GND")
		)
	)
	(footprint ""
		(layer "B.Cu")
		(at 45.5676 -4.1148 -90)
		(property "Reference" "R18"
			(at 0 0 90)
			(layer "B.SilkS")
			(hide yes)
			(effects
				(font
					(size 1.27 1.27)
				)
				(justify mirror)
			)
		)
		(property "Value" ""
			(at 0 0 90)
			(layer "B.Fab")
			(effects
				(font
					(size 1.27 1.27)
				)
				(justify mirror)
			)
		)
		(duplicate_pad_numbers_are_jumpers no)
		(fp_line
			(start -0.7874 0.4064)
			(end 0.7874 0.4064)
			(stroke
				(width 0.1524)
				(type default)
			)
			(layer "B.SilkS")
		)
		(fp_line
			(start 0.7874 0.4064)
			(end 0.7874 -0.4064)
			(stroke
				(width 0.1524)
				(type default)
			)
			(layer "B.SilkS")
		)
		(fp_line
			(start -0.7874 -0.4064)
			(end -0.7874 0.4064)
			(stroke
				(width 0.1524)
				(type default)
			)
			(layer "B.SilkS")
		)
		(fp_line
			(start 0.7874 -0.4064)
			(end -0.7874 -0.4064)
			(stroke
				(width 0.1524)
				(type default)
			)
			(layer "B.SilkS")
		)
		(fp_line
			(start -0.67945 0.3048)
			(end -0.120396 0.3048)
			(stroke
				(width 0.1)
				(type default)
			)
			(layer "B.Fab")
		)
		(fp_line
			(start -0.120396 0.3048)
			(end -0.120396 0.2794)
			(stroke
				(width 0.1)
				(type default)
			)
			(layer "B.Fab")
		)
		(fp_line
			(start 0.12065 0.3048)
			(end 0.67945 0.3048)
			(stroke
				(width 0.1)
				(type default)
			)
			(layer "B.Fab")
		)
		(fp_line
			(start 0.67945 0.3048)
			(end 0.67945 -0.305054)
			(stroke
				(width 0.1)
				(type default)
			)
			(layer "B.Fab")
		)
		(fp_line
			(start -0.120396 0.2794)
			(end 0.12065 0.2794)
			(stroke
				(width 0.1)
				(type default)
			)
			(layer "B.Fab")
		)
		(fp_line
			(start 0.12065 0.2794)
			(end 0.12065 0.3048)
			(stroke
				(width 0.1)
				(type default)
			)
			(layer "B.Fab")
		)
		(fp_line
			(start -0.12065 -0.2794)
			(end -0.12065 -0.3048)
			(stroke
				(width 0.1)
				(type default)
			)
			(layer "B.Fab")
		)
		(fp_line
			(start 0.12065 -0.2794)
			(end -0.12065 -0.2794)
			(stroke
				(width 0.1)
				(type default)
			)
			(layer "B.Fab")
		)
		(fp_line
			(start -0.67945 -0.3048)
			(end -0.67945 0.3048)
			(stroke
				(width 0.1)
				(type default)
			)
			(layer "B.Fab")
		)
		(fp_line
			(start -0.12065 -0.3048)
			(end -0.67945 -0.3048)
			(stroke
				(width 0.1)
				(type default)
			)
			(layer "B.Fab")
		)
		(fp_line
			(start 0.12065 -0.305054)
			(end 0.12065 -0.2794)
			(stroke
				(width 0.1)
				(type default)
			)
			(layer "B.Fab")
		)
		(fp_line
			(start 0.67945 -0.305054)
			(end 0.12065 -0.305054)
			(stroke
				(width 0.1)
				(type default)
			)
			(layer "B.Fab")
		)
		(pad "1" smd circle
			(at 0.40005 0 90)
			(size 0 0)
			(layers "B.Cu" "B.Mask" "B.Paste")
			(net "P5V_AUX")
		)
		(pad "2" smd circle
			(at -0.40005 0 90)
			(size 0 0)
			(layers "B.Cu" "B.Mask" "B.Paste")
			(net "BMC_DDC_BUF_PWR")
		)
	)
	(footprint ""
		(layer "B.Cu")
		(at 51.255168 -69.397372 -90)
		(property "Reference" "R790"
			(at 0 0 90)
			(layer "B.SilkS")
			(hide yes)
			(effects
				(font
					(size 1.27 1.27)
				)
				(justify mirror)
			)
		)
		(property "Value" ""
			(at 0 0 90)
			(layer "B.Fab")
			(effects
				(font
					(size 1.27 1.27)
				)
				(justify mirror)
			)
		)
		(duplicate_pad_numbers_are_jumpers no)
		(fp_line
			(start -0.7874 0.4064)
			(end 0.7874 0.4064)
			(stroke
				(width 0.1524)
				(type default)
			)
			(layer "B.SilkS")
		)
		(fp_line
			(start 0.7874 0.4064)
			(end 0.7874 -0.4064)
			(stroke
				(width 0.1524)
				(type default)
			)
			(layer "B.SilkS")
		)
		(fp_line
			(start -0.7874 -0.4064)
			(end -0.7874 0.4064)
			(stroke
				(width 0.1524)
				(type default)
			)
			(layer "B.SilkS")
		)
		(fp_line
			(start 0.7874 -0.4064)
			(end -0.7874 -0.4064)
			(stroke
				(width 0.1524)
				(type default)
			)
			(layer "B.SilkS")
		)
		(fp_line
			(start -0.67945 0.3048)
			(end -0.120396 0.3048)
			(stroke
				(width 0.1)
				(type default)
			)
			(layer "B.Fab")
		)
		(fp_line
			(start -0.120396 0.3048)
			(end -0.120396 0.2794)
			(stroke
				(width 0.1)
				(type default)
			)
			(layer "B.Fab")
		)
		(fp_line
			(start 0.12065 0.3048)
			(end 0.67945 0.3048)
			(stroke
				(width 0.1)
				(type default)
			)
			(layer "B.Fab")
		)
		(fp_line
			(start 0.67945 0.3048)
			(end 0.67945 -0.305054)
			(stroke
				(width 0.1)
				(type default)
			)
			(layer "B.Fab")
		)
		(fp_line
			(start -0.120396 0.2794)
			(end 0.12065 0.2794)
			(stroke
				(width 0.1)
				(type default)
			)
			(layer "B.Fab")
		)
		(fp_line
			(start 0.12065 0.2794)
			(end 0.12065 0.3048)
			(stroke
				(width 0.1)
				(type default)
			)
			(layer "B.Fab")
		)
		(fp_line
			(start -0.12065 -0.2794)
			(end -0.12065 -0.3048)
			(stroke
				(width 0.1)
				(type default)
			)
			(layer "B.Fab")
		)
		(fp_line
			(start 0.12065 -0.2794)
			(end -0.12065 -0.2794)
			(stroke
				(width 0.1)
				(type default)
			)
			(layer "B.Fab")
		)
		(fp_line
			(start -0.67945 -0.3048)
			(end -0.67945 0.3048)
			(stroke
				(width 0.1)
				(type default)
			)
			(layer "B.Fab")
		)
		(fp_line
			(start -0.12065 -0.3048)
			(end -0.67945 -0.3048)
			(stroke
				(width 0.1)
				(type default)
			)
			(layer "B.Fab")
		)
		(fp_line
			(start 0.12065 -0.305054)
			(end 0.12065 -0.2794)
			(stroke
				(width 0.1)
				(type default)
			)
			(layer "B.Fab")
		)
		(fp_line
			(start 0.67945 -0.305054)
			(end 0.12065 -0.305054)
			(stroke
				(width 0.1)
				(type default)
			)
			(layer "B.Fab")
		)
		(pad "1" smd circle
			(at 0.40005 0 90)
			(size 0 0)
			(layers "B.Cu" "B.Mask" "B.Paste")
			(net "P3V3_SENSOR")
		)
		(pad "2" smd circle
			(at -0.40005 0 90)
			(size 0 0)
			(layers "B.Cu" "B.Mask" "B.Paste")
			(net "GND")
		)
	)
	(footprint ""
		(layer "B.Cu")
		(at 28.702 -37.581078 90)
		(property "Reference" "D9"
			(at -3.799078 -2.71907 270)
			(unlocked yes)
			(layer "B.SilkS")
			(effects
				(font
					(size 0.7874 0.5842)
					(thickness 0.1524)
				)
				(justify left mirror)
			)
		)
		(property "Value" ""
			(at 0 0 90)
			(layer "B.Fab")
			(effects
				(font
					(size 1.27 1.27)
				)
				(justify mirror)
			)
		)
		(duplicate_pad_numbers_are_jumpers no)
		(fp_line
			(start 2.262378 -0.899922)
			(end 2.262378 0.899922)
			(stroke
				(width 0.1524)
				(type default)
			)
			(layer "B.SilkS")
		)
		(fp_line
			(start -2.567178 -0.899922)
			(end 2.262378 -0.899922)
			(stroke
				(width 0.1524)
				(type default)
			)
			(layer "B.SilkS")
		)
		(fp_line
			(start 0.3175 -0.508)
			(end 0.3175 0.508)
			(stroke
				(width 0.1524)
				(type default)
			)
			(layer "B.SilkS")
		)
		(fp_line
			(start -0.3175 -0.508)
			(end -0.3175 0.508)
			(stroke
				(width 0.1524)
				(type default)
			)
			(layer "B.SilkS")
		)
		(fp_line
			(start 0.8255 0)
			(end 0.3175 0)
			(stroke
				(width 0.1524)
				(type default)
			)
			(layer "B.SilkS")
		)
		(fp_line
			(start -0.3175 0)
			(end 0.3175 -0.508)
			(stroke
				(width 0.1524)
				(type default)
			)
			(layer "B.SilkS")
		)
		(fp_line
			(start -0.3175 0)
			(end -0.8255 0)
			(stroke
				(width 0.1524)
				(type default)
			)
			(layer "B.SilkS")
		)
		(fp_line
			(start 0.3175 0.508)
			(end -0.3175 0)
			(stroke
				(width 0.1524)
				(type default)
			)
			(layer "B.SilkS")
		)
		(fp_line
			(start 2.262378 0.899922)
			(end -2.567178 0.899922)
			(stroke
				(width 0.1524)
				(type default)
			)
			(layer "B.SilkS")
		)
		(fp_line
			(start -2.567178 0.899922)
			(end -2.567178 -0.899922)
			(stroke
				(width 0.1524)
				(type default)
			)
			(layer "B.SilkS")
		)
		(fp_poly
			(pts
				(xy -2.567178 -0.899922) (xy -2.186178 -0.899922) (xy -2.186178 0.899922) (xy -2.567178 0.899922)
			)
			(stroke
				(width 0)
				(type default)
			)
			(fill yes)
			(layer "B.SilkS")
		)
		(fp_line
			(start 1.400048 -0.899922)
			(end 1.400048 0.899922)
			(stroke
				(width 0.1)
				(type default)
			)
			(layer "B.Fab")
		)
		(fp_line
			(start -1.400048 -0.899922)
			(end 1.400048 -0.899922)
			(stroke
				(width 0.1)
				(type default)
			)
			(layer "B.Fab")
		)
		(fp_line
			(start 1.400048 0.899922)
			(end -1.400048 0.899922)
			(stroke
				(width 0.1)
				(type default)
			)
			(layer "B.Fab")
		)
		(fp_line
			(start -1.400048 0.899922)
			(end -1.400048 -0.899922)
			(stroke
				(width 0.1)
				(type default)
			)
			(layer "B.Fab")
		)
		(fp_text user "+"
			(at 3.19405 0.0254 0)
			(unlocked yes)
			(layer "B.SilkS")
			(effects
				(font
					(size 1.905 1.4224)
					(thickness 0.1524)
				)
				(justify left mirror)
			)
		)
		(fp_text user "-"
			(at -3.937762 0.241046 270)
			(unlocked yes)
			(layer "B.SilkS")
			(effects
				(font
					(size 1.905 1.4224)
					(thickness 0.1524)
				)
				(justify left mirror)
			)
		)
		(fp_text user "-"
			(at -3.937762 0.241046 270)
			(unlocked yes)
			(layer "B.Fab")
			(effects
				(font
					(size 1.905 1.4224)
					(thickness 0.1524)
				)
				(justify left mirror)
			)
		)
		(fp_text user "+"
			(at 3.29565 0.6858 0)
			(unlocked yes)
			(layer "B.Fab")
			(effects
				(font
					(size 1.905 1.4224)
					(thickness 0.1524)
				)
				(justify left mirror)
			)
		)
		(pad "A" smd rect
			(at 1.640078 0 270)
			(size 0.9906 1.2192)
			(layers "B.Cu" "B.Mask" "B.Paste")
			(net "P5V_AUX")
		)
		(pad "C" smd rect
			(at -1.640078 0 270)
			(size 0.9906 1.2192)
			(layers "B.Cu" "B.Mask" "B.Paste")
			(net "CRT_VCC5")
		)
	)
)
